# SCM (Grand Teton) — schematic netlist excerpt (pin names and nets, part order shuffled) for the footprints in the layout excerpt that follows; sources: Cadence DE-HDL packaged netlist, KiCad conversion of 12092022_DA0F0TMDCD0_F0T_Management_Board_D_brd_V3_OCP.brd

J25  PICOPROBE_BXA  DELTA-L 4.0 EMPTY  pkg TRIANG_LAUNCH_3PXB  page 58
  \1_p\  = 85_10INCH_TOP_DN
  \2_n\  = 85_10INCH_TOP_DP
  \3_g\  = GND_P1

(kicad_pcb
	(version 20260206)
	(generator "pcbnew")
	(generator_version "10.0")
	(general
		(thickness 1.6)
		(legacy_teardrops no)
	)
	(paper "A4")
	(title_block
		(title "12092022_DA0F0TMDCD0_F0T_Management_Board_D_brd_V3_OCP.brd")
		(comment 1 "Grand Teton / footprints 142-142 of 1440")
	)
	(layers
		(0 "F.Cu" signal "TOP")
		(4 "In1.Cu" signal "GND")
		(6 "In2.Cu" signal "IN1")
		(8 "In3.Cu" signal "GND1")
		(10 "In4.Cu" signal "IN2")
		(12 "In5.Cu" signal "VCC")
		(14 "In6.Cu" signal "VCC1")
		(16 "In7.Cu" signal "IN3")
		(18 "In8.Cu" signal "GND2")
		(20 "In9.Cu" signal "IN4")
		(22 "In10.Cu" signal "GND3")
		(2 "B.Cu" signal "BOTTOM")
		(9 "F.Adhes" user "F.Adhesive")
		(11 "B.Adhes" user "B.Adhesive")
		(13 "F.Paste" user "Package Geometry/Pastemask Top")
		(15 "B.Paste" user "Package Geometry/Pastemask Bottom")
		(5 "F.SilkS" user "Ref Des/Silkscreen Top")
		(7 "B.SilkS" user "Ref Des/Silkscreen Bottom")
		(1 "F.Mask" user "Board Geometry/Soldermask Top")
		(3 "B.Mask" user "Board Geometry/Soldermask Bottom")
		(17 "Dwgs.User" user "User.Drawings")
		(19 "Cmts.User" user "User.Comments")
		(21 "Eco1.User" user "User.Eco1")
		(23 "Eco2.User" user "User.Eco2")
		(25 "Edge.Cuts" user "Board Geometry/Outline")
		(27 "Margin" user)
		(31 "F.CrtYd" user "Package Geometry/Place Bound Top")
		(29 "B.CrtYd" user "Package Geometry/Place Bound Bottom")
		(35 "F.Fab" user "Ref Des/Assembly Top")
		(33 "B.Fab" user "Ref Des/Assembly Bottom")
	)
	(footprint ""
		(layer "F.Cu")
		(at 103.8225 18.001488 90)
		(property "Reference" "J25"
			(at -6.128512 1.48717 90)
			(unlocked yes)
			(layer "F.SilkS")
			(effects
				(font
					(size 0.7874 0.5842)
					(thickness 0.1524)
				)
				(justify left)
			)
		)
		(property "Value" ""
			(at 0 0 90)
			(layer "F.Fab")
			(effects
				(font
					(size 1.27 1.27)
				)
			)
		)
		(duplicate_pad_numbers_are_jumpers no)
		(fp_line
			(start 1.2192 -2.1082)
			(end 1.2192 -0.458978)
			(stroke
				(width 0.1524)
				(type default)
			)
			(layer "F.SilkS")
		)
		(fp_line
			(start -1.2192 -2.1082)
			(end 1.2192 -2.1082)
			(stroke
				(width 0.1524)
				(type default)
			)
			(layer "F.SilkS")
		)
		(fp_line
			(start 1.2192 0.452882)
			(end 1.2192 2.1082)
			(stroke
				(width 0.1524)
				(type default)
			)
			(layer "F.SilkS")
		)
		(fp_line
			(start 1.2192 2.1082)
			(end -1.2192 2.1082)
			(stroke
				(width 0.1524)
				(type default)
			)
			(layer "F.SilkS")
		)
		(fp_line
			(start -1.2192 2.1082)
			(end -1.2192 -2.1082)
			(stroke
				(width 0.1524)
				(type default)
			)
			(layer "F.SilkS")
		)
		(pad "" np_thru_hole circle
			(at -2.8829 -1.27)
			(size 1.0414 1.0414)
			(drill 1.0414)
			(layers "*.Cu" "*.Mask")
			(clearance 0.381)
			(thermal_gap 0.381)
		)
		(pad "" np_thru_hole circle
			(at -2.8829 1.27)
			(size 1.0414 1.0414)
			(drill 1.0414)
			(layers "*.Cu" "*.Mask")
			(clearance 0.381)
			(thermal_gap 0.381)
		)
		(pad "" np_thru_hole circle
			(at 3.4671 -1.27)
			(size 1.0414 1.0414)
			(drill 1.0414)
			(layers "*.Cu" "*.Mask")
			(clearance 0.381)
			(thermal_gap 0.381)
		)
		(pad "" np_thru_hole circle
			(at 3.4671 1.27)
			(size 1.0414 1.0414)
			(drill 1.0414)
			(layers "*.Cu" "*.Mask")
			(clearance 0.381)
			(thermal_gap 0.381)
		)
		(pad "1" smd rect
			(at 0.8255 -0.249936)
			(size 0.3048 0.508)
			(layers "F.Cu" "F.Mask" "F.Paste")
			(net "85_10INCH_TOP_DN")
		)
		(pad "2" smd rect
			(at 0.8255 0.249936)
			(size 0.3048 0.508)
			(layers "F.Cu" "F.Mask" "F.Paste")
			(net "85_10INCH_TOP_DP")
		)
		(pad "3" smd circle
			(at 0 0 90)
			(size 0 0)
			(layers "F.Cu" "F.Mask" "F.Paste")
			(net "GND_P1")
		)
		(zone
			(layer "F.Cu")
			(hatch none 0.5)
			(connect_pads
				(clearance 0)
			)
			(min_thickness 0.25)
			(keepout
				(tracks not_allowed)
				(vias allowed)
				(pads allowed)
				(copperpour not_allowed)
				(footprints allowed)
			)
			(placement
				(enabled no)
				(sheetname "")
			)
			(fill
				(thermal_gap 0.5)
				(thermal_bridge_width 0.5)
				(island_removal_mode 0)
			)
			(polygon
				(pts
					(xy 103.27386 16.883888) (xy 103.369364 16.883888) (xy 103.369364 17.480788) (xy 103.775764 17.480788)
					(xy 103.775764 16.883888) (xy 103.869236 16.883888) (xy 103.869236 17.480788) (xy 104.275636 17.480788)
					(xy 104.275636 16.883888) (xy 104.37114 16.883888) (xy 104.37114 17.582388) (xy 103.27386 17.582388)
				)
			)
		)
		(zone
			(layers "F.Cu" "B.Cu" "In1.Cu" "In2.Cu" "In3.Cu" "In4.Cu" "In5.Cu" "In6.Cu"
				"In7.Cu" "In8.Cu" "In9.Cu" "In10.Cu"
			)
			(hatch none 0.5)
			(connect_pads
				(clearance 0)
			)
			(min_thickness 0.25)
			(keepout
				(tracks not_allowed)
				(vias allowed)
				(pads allowed)
				(copperpour not_allowed)
				(footprints allowed)
			)
			(placement
				(enabled no)
				(sheetname "")
			)
			(fill
				(thermal_gap 0.5)
				(thermal_bridge_width 0.5)
				(island_removal_mode 0)
			)
			(polygon
				(pts
					(arc
						(start 103.4796 14.534388)
						(mid 101.6254 14.534388)
						(end 103.4796 14.534388)
					)
				)
			)
		)
		(zone
			(layers "F.Cu" "B.Cu" "In1.Cu" "In2.Cu" "In3.Cu" "In4.Cu" "In5.Cu" "In6.Cu"
				"In7.Cu" "In8.Cu" "In9.Cu" "In10.Cu"
			)
			(hatch none 0.5)
			(connect_pads
				(clearance 0)
			)
			(min_thickness 0.25)
			(keepout
				(tracks not_allowed)
				(vias allowed)
				(pads allowed)
				(copperpour not_allowed)
				(footprints allowed)
			)
			(placement
				(enabled no)
				(sheetname "")
			)
			(fill
				(thermal_gap 0.5)
				(thermal_bridge_width 0.5)
				(island_removal_mode 0)
			)
			(polygon
				(pts
					(arc
						(start 103.4796 20.884388)
						(mid 101.6254 20.884388)
						(end 103.4796 20.884388)
					)
				)
			)
		)
		(zone
			(layers "F.Cu" "B.Cu" "In1.Cu" "In2.Cu" "In3.Cu" "In4.Cu" "In5.Cu" "In6.Cu"
				"In7.Cu" "In8.Cu" "In9.Cu" "In10.Cu"
			)
			(hatch none 0.5)
			(connect_pads
				(clearance 0)
			)
			(min_thickness 0.25)
			(keepout
				(tracks not_allowed)
				(vias allowed)
				(pads allowed)
				(copperpour not_allowed)
				(footprints allowed)
			)
			(placement
				(enabled no)
				(sheetname "")
			)
			(fill
				(thermal_gap 0.5)
				(thermal_bridge_width 0.5)
				(island_removal_mode 0)
			)
			(polygon
				(pts
					(arc
						(start 106.0196 14.534388)
						(mid 104.1654 14.534388)
						(end 106.0196 14.534388)
					)
				)
			)
		)
		(zone
			(layers "F.Cu" "B.Cu" "In1.Cu" "In2.Cu" "In3.Cu" "In4.Cu" "In5.Cu" "In6.Cu"
				"In7.Cu" "In8.Cu" "In9.Cu" "In10.Cu"
			)
			(hatch none 0.5)
			(connect_pads
				(clearance 0)
			)
			(min_thickness 0.25)
			(keepout
				(tracks not_allowed)
				(vias allowed)
				(pads allowed)
				(copperpour not_allowed)
				(footprints allowed)
			)
			(placement
				(enabled no)
				(sheetname "")
			)
			(fill
				(thermal_gap 0.5)
				(thermal_bridge_width 0.5)
				(island_removal_mode 0)
			)
			(polygon
				(pts
					(arc
						(start 106.0196 20.884388)
						(mid 104.1654 20.884388)
						(end 106.0196 20.884388)
					)
				)
			)
		)
	)
)
